# BASEBOARD_FAB2 (Tioga Pass) — schematic netlist excerpt (pin names and nets, part order shuffled) for the footprints in the layout excerpt that follows; sources: Cadence DE-HDL packaged netlist, KiCad conversion of Wiwynn_Tioga_Pass_MB.brd

R6B5  RES  0.0 5% CHIP  pkg 0402  page 21 : A = SVID_CLK1_CPU0 ; B = SVID_CLK1_CPU0_R
R12W27  RES  0.0 5% EMPTY  pkg 0402  page 215 : A = TP_PVDDQ_ABC_MP2 ; B = PWRGD_PVDDQ_ABC
C7G7  CAP  0.22UF 16V 10% X7R  pkg 0402  page 105 : A = P3E_CPU0_PE2_SS_TXN<14> ; B = P3E_CPU0_PE2_SS_C_TXN<14>

(kicad_pcb
	(version 20260206)
	(generator "pcbnew")
	(generator_version "10.0")
	(general
		(thickness 1.6)
		(legacy_teardrops no)
	)
	(paper "A4")
	(title_block
		(title "Wiwynn_Tioga_Pass_MB.brd")
		(comment 1 "Tioga Pass / footprints 2133-2135 of 4770")
	)
	(layers
		(0 "F.Cu" signal "TOP")
		(4 "In1.Cu" signal "L2GND")
		(6 "In2.Cu" signal "L3")
		(8 "In3.Cu" signal "L4GND")
		(10 "In4.Cu" signal "L5")
		(12 "In5.Cu" signal "L6GND")
		(14 "In6.Cu" signal "L7VCC")
		(16 "In7.Cu" signal "L8VCC")
		(18 "In8.Cu" signal "L9GND")
		(20 "In9.Cu" signal "L10")
		(22 "In10.Cu" signal "L11GND")
		(24 "In11.Cu" signal "L12")
		(26 "In12.Cu" signal "L13GND")
		(2 "B.Cu" signal "BOTTOM")
		(9 "F.Adhes" user "F.Adhesive")
		(11 "B.Adhes" user "B.Adhesive")
		(13 "F.Paste" user "Package Geometry/Pastemask Top")
		(15 "B.Paste" user "Package Geometry/Pastemask Bottom")
		(5 "F.SilkS" user "Ref Des/Silkscreen Top")
		(7 "B.SilkS" user "Ref Des/Silkscreen Bottom")
		(1 "F.Mask" user "Board Geometry/Soldermask Top")
		(3 "B.Mask" user "Board Geometry/Soldermask Bottom")
		(17 "Dwgs.User" user "User.Drawings")
		(19 "Cmts.User" user "User.Comments")
		(21 "Eco1.User" user "User.Eco1")
		(23 "Eco2.User" user "User.Eco2")
		(25 "Edge.Cuts" user "Board Geometry/Outline")
		(27 "Margin" user)
		(31 "F.CrtYd" user "Package Geometry/Place Bound Top")
		(29 "B.CrtYd" user "Package Geometry/Place Bound Bottom")
		(35 "F.Fab" user "Ref Des/Assembly Top")
		(33 "B.Fab" user "Ref Des/Assembly Bottom")
	)
	(footprint ""
		(layer "F.Cu")
		(at 338.836 -14.732 -90)
		(property "Reference" "R12W27"
			(at -0.8382 -0.67818 270)
			(unlocked yes)
			(layer "F.SilkS")
			(effects
				(font
					(size 0.4064 0.254)
					(thickness 0.1524)
				)
				(justify left)
			)
		)
		(property "Value" ""
			(at 0 0 270)
			(layer "F.Fab")
			(effects
				(font
					(size 1.27 1.27)
				)
			)
		)
		(duplicate_pad_numbers_are_jumpers no)
		(fp_poly
			(pts
				(xy -0.2794 -0.1016) (xy 0.2794 -0.1016) (xy 0.2794 0.9906) (xy -0.2794 0.9906)
			)
			(stroke
				(width 0)
				(type default)
			)
			(fill no)
			(layer "F.CrtYd")
		)
		(fp_line
			(start -0.2794 0.9906)
			(end 0.2794 0.9906)
			(stroke
				(width 0.1)
				(type default)
			)
			(layer "F.Fab")
		)
		(fp_line
			(start 0.2794 0.9906)
			(end 0.2794 -0.1016)
			(stroke
				(width 0.1)
				(type default)
			)
			(layer "F.Fab")
		)
		(fp_line
			(start -0.2794 -0.1016)
			(end -0.2794 0.9906)
			(stroke
				(width 0.1)
				(type default)
			)
			(layer "F.Fab")
		)
		(fp_line
			(start 0.2794 -0.1016)
			(end -0.2794 -0.1016)
			(stroke
				(width 0.1)
				(type default)
			)
			(layer "F.Fab")
		)
		(pad "1" smd rect
			(at 0 0 270)
			(size 0.508 0.508)
			(layers "F.Cu" "F.Mask" "F.Paste")
			(net "TP_PVDDQ_ABC_MP2")
		)
		(pad "2" smd rect
			(at 0 0.889 270)
			(size 0.508 0.508)
			(layers "F.Cu" "F.Mask" "F.Paste")
			(net "PWRGD_PVDDQ_ABC")
		)
		(zone
			(layer "F.Cu")
			(hatch none 0.5)
			(connect_pads
				(clearance 0)
			)
			(min_thickness 0.25)
			(keepout
				(tracks not_allowed)
				(vias allowed)
				(pads allowed)
				(copperpour not_allowed)
				(footprints allowed)
			)
			(placement
				(enabled no)
				(sheetname "")
			)
			(fill
				(thermal_gap 0.5)
				(thermal_bridge_width 0.5)
				(island_removal_mode 0)
			)
			(polygon
				(pts
					(xy 338.201 -14.986) (xy 338.201 -14.478) (xy 338.582 -14.478) (xy 338.582 -14.986)
				)
			)
		)
		(zone
			(layer "F.Cu")
			(hatch none 0.5)
			(connect_pads
				(clearance 0)
			)
			(min_thickness 0.25)
			(keepout
				(tracks allowed)
				(vias not_allowed)
				(pads allowed)
				(copperpour not_allowed)
				(footprints allowed)
			)
			(placement
				(enabled no)
				(sheetname "")
			)
			(fill
				(thermal_gap 0.5)
				(thermal_bridge_width 0.5)
				(island_removal_mode 0)
			)
			(polygon
				(pts
					(xy 338.582 -14.986) (xy 338.582 -14.478) (xy 338.201 -14.478) (xy 338.201 -14.986)
				)
			)
		)
	)
	(footprint ""
		(layer "F.Cu")
		(at 364.600744 -10.916158)
		(property "Reference" "C7G7"
			(at 0 0 0)
			(layer "F.SilkS")
			(hide yes)
			(effects
				(font
					(size 1.27 1.27)
				)
			)
		)
		(property "Value" ""
			(at 0 0 0)
			(layer "F.Fab")
			(effects
				(font
					(size 1.27 1.27)
				)
			)
		)
		(duplicate_pad_numbers_are_jumpers no)
		(fp_rect
			(start -0.3048 0.9906)
			(end 0.3048 -0.1016)
			(stroke
				(width 0)
				(type default)
			)
			(fill no)
			(layer "F.CrtYd")
		)
		(fp_line
			(start -0.3048 -0.1016)
			(end -0.3048 0.9906)
			(stroke
				(width 0.1)
				(type default)
			)
			(layer "F.Fab")
		)
		(fp_line
			(start -0.3048 0.9906)
			(end 0.3048 0.9906)
			(stroke
				(width 0.1)
				(type default)
			)
			(layer "F.Fab")
		)
		(fp_line
			(start 0.3048 -0.1016)
			(end -0.3048 -0.1016)
			(stroke
				(width 0.1)
				(type default)
			)
			(layer "F.Fab")
		)
		(fp_line
			(start 0.3048 0.9906)
			(end 0.3048 -0.1016)
			(stroke
				(width 0.1)
				(type default)
			)
			(layer "F.Fab")
		)
		(pad "1" smd rect
			(at 0 0)
			(size 0.508 0.508)
			(layers "F.Cu" "F.Mask" "F.Paste")
			(net "P3E_CPU0_PE2_SS_TXN<14>")
		)
		(pad "2" smd rect
			(at 0 0.889)
			(size 0.508 0.508)
			(layers "F.Cu" "F.Mask" "F.Paste")
			(net "P3E_CPU0_PE2_SS_C_TXN<14>")
		)
		(zone
			(layer "F.Cu")
			(hatch none 0.5)
			(connect_pads
				(clearance 0)
			)
			(min_thickness 0.25)
			(keepout
				(tracks allowed)
				(vias not_allowed)
				(pads allowed)
				(copperpour not_allowed)
				(footprints allowed)
			)
			(placement
				(enabled no)
				(sheetname "")
			)
			(fill
				(thermal_gap 0.5)
				(thermal_bridge_width 0.5)
				(island_removal_mode 0)
			)
			(polygon
				(pts
					(xy 364.346744 -10.281158) (xy 364.854744 -10.281158) (xy 364.854744 -10.662158) (xy 364.346744 -10.662158)
				)
			)
		)
		(zone
			(layer "F.Cu")
			(hatch none 0.5)
			(connect_pads
				(clearance 0)
			)
			(min_thickness 0.25)
			(keepout
				(tracks not_allowed)
				(vias allowed)
				(pads allowed)
				(copperpour not_allowed)
				(footprints allowed)
			)
			(placement
				(enabled no)
				(sheetname "")
			)
			(fill
				(thermal_gap 0.5)
				(thermal_bridge_width 0.5)
				(island_removal_mode 0)
			)
			(polygon
				(pts
					(xy 364.346744 -10.281158) (xy 364.854744 -10.281158) (xy 364.854744 -10.662158) (xy 364.346744 -10.662158)
				)
			)
		)
	)
	(footprint ""
		(layer "F.Cu")
		(at 324.282816 -128.025652 180)
		(property "Reference" "R6B5"
			(at 0 0 180)
			(layer "F.SilkS")
			(hide yes)
			(effects
				(font
					(size 1.27 1.27)
				)
			)
		)
		(property "Value" ""
			(at 0 0 180)
			(layer "F.Fab")
			(effects
				(font
					(size 1.27 1.27)
				)
			)
		)
		(duplicate_pad_numbers_are_jumpers no)
		(fp_poly
			(pts
				(xy -0.2794 -0.1016) (xy 0.2794 -0.1016) (xy 0.2794 0.9906) (xy -0.2794 0.9906)
			)
			(stroke
				(width 0)
				(type default)
			)
			(fill no)
			(layer "F.CrtYd")
		)
		(fp_line
			(start 0.2794 0.9906)
			(end 0.2794 -0.1016)
			(stroke
				(width 0.1)
				(type default)
			)
			(layer "F.Fab")
		)
		(fp_line
			(start 0.2794 -0.1016)
			(end -0.2794 -0.1016)
			(stroke
				(width 0.1)
				(type default)
			)
			(layer "F.Fab")
		)
		(fp_line
			(start -0.2794 0.9906)
			(end 0.2794 0.9906)
			(stroke
				(width 0.1)
				(type default)
			)
			(layer "F.Fab")
		)
		(fp_line
			(start -0.2794 -0.1016)
			(end -0.2794 0.9906)
			(stroke
				(width 0.1)
				(type default)
			)
			(layer "F.Fab")
		)
		(pad "1" smd rect
			(at 0 0 180)
			(size 0.508 0.508)
			(layers "F.Cu" "F.Mask" "F.Paste")
			(net "SVID_CLK1_CPU0")
		)
		(pad "2" smd rect
			(at 0 0.889 180)
			(size 0.508 0.508)
			(layers "F.Cu" "F.Mask" "F.Paste")
			(net "SVID_CLK1_CPU0_R")
		)
		(zone
			(layer "F.Cu")
			(hatch none 0.5)
			(connect_pads
				(clearance 0)
			)
			(min_thickness 0.25)
			(keepout
				(tracks not_allowed)
				(vias allowed)
				(pads allowed)
				(copperpour not_allowed)
				(footprints allowed)
			)
			(placement
				(enabled no)
				(sheetname "")
			)
			(fill
				(thermal_gap 0.5)
				(thermal_bridge_width 0.5)
				(island_removal_mode 0)
			)
			(polygon
				(pts
					(xy 324.536816 -128.660652) (xy 324.028816 -128.660652) (xy 324.028816 -128.279652) (xy 324.536816 -128.279652)
				)
			)
		)
		(zone
			(layer "F.Cu")
			(hatch none 0.5)
			(connect_pads
				(clearance 0)
			)
			(min_thickness 0.25)
			(keepout
				(tracks allowed)
				(vias not_allowed)
				(pads allowed)
				(copperpour not_allowed)
				(footprints allowed)
			)
			(placement
				(enabled no)
				(sheetname "")
			)
			(fill
				(thermal_gap 0.5)
				(thermal_bridge_width 0.5)
				(island_removal_mode 0)
			)
			(polygon
				(pts
					(xy 324.536816 -128.279652) (xy 324.028816 -128.279652) (xy 324.028816 -128.660652) (xy 324.536816 -128.660652)
				)
			)
		)
	)
)
